(kicad_pcb
	(version 20260206)
	(generator "pcbnew")
	(generator_version "10.0")
	(general
		(thickness 1.6)
		(legacy_teardrops no)
	)
	(paper "A4")
	(title_block
		(title "Bryce Canyon_R.DPB_16317-1_OCP.brd")
		(comment 1 "Bryce Canyon / footprints 753-759 of 2099")
	)
	(layers
		(0 "F.Cu" signal "TOP")
		(4 "In1.Cu" signal "L2GND")
		(6 "In2.Cu" signal "L3")
		(8 "In3.Cu" signal "L4VCC")
		(10 "In4.Cu" signal "L5VCC")
		(12 "In5.Cu" signal "L6")
		(14 "In6.Cu" signal "L7GND")
		(2 "B.Cu" signal "BOTTOM")
		(9 "F.Adhes" user "F.Adhesive")
		(11 "B.Adhes" user "B.Adhesive")
		(13 "F.Paste" user "Package Geometry/Pastemask Top")
		(15 "B.Paste" user "Package Geometry/Pastemask Bottom")
		(5 "F.SilkS" user "Ref Des/Silkscreen Top")
		(7 "B.SilkS" user "Ref Des/Silkscreen Bottom")
		(1 "F.Mask" user "Board Geometry/Soldermask Top")
		(3 "B.Mask" user "Board Geometry/Soldermask Bottom")
		(17 "Dwgs.User" user "User.Drawings")
		(19 "Cmts.User" user "User.Comments")
		(21 "Eco1.User" user "User.Eco1")
		(23 "Eco2.User" user "User.Eco2")
		(25 "Edge.Cuts" user "Board Geometry/Outline")
		(27 "Margin" user)
		(31 "F.CrtYd" user "Package Geometry/Place Bound Top")
		(29 "B.CrtYd" user "Package Geometry/Place Bound Bottom")
		(35 "F.Fab" user "Ref Des/Assembly Top")
		(33 "B.Fab" user "Ref Des/Assembly Bottom")
	)
	(footprint ""
		(layer "F.Cu")
		(at 239.268 -226.06 -90)
		(property "Reference" "C18"
			(at 0 0 270)
			(layer "F.SilkS")
			(hide yes)
			(effects
				(font
					(size 1.27 1.27)
				)
			)
		)
		(property "Value" "SCD1U16V2KX-3GP"
			(at 1.1811 -2.7051 270)
			(unlocked yes)
			(layer "F.Fab")
			(hide yes)
			(effects
				(font
					(size 1.016 1.016)
					(thickness 0.1524)
				)
			)
		)
		(property "Device Type" "C402H22"
			(at 1.1811 -4.2291 270)
			(unlocked yes)
			(layer "F.Fab")
			(hide yes)
			(effects
				(font
					(size 1.016 1.016)
					(thickness 0.1524)
				)
			)
		)
		(duplicate_pad_numbers_are_jumpers no)
		(fp_rect
			(start -0.4318 0.9525)
			(end 0.4318 -0.9525)
			(stroke
				(width 0)
				(type default)
			)
			(fill no)
			(layer "F.CrtYd")
		)
		(fp_rect
			(start -0.4318 0.9525)
			(end 0.4318 -0.9525)
			(stroke
				(width 0)
				(type default)
			)
			(fill no)
			(layer "F.Fab")
		)
		(pad "1" smd custom
			(at 0 -0.4445 270)
			(size 0.1524 0.1524)
			(layers "F.Cu" "F.Mask" "F.Paste")
			(net "GPIO_VCC_U10")
			(options
				(clearance outline)
				(anchor circle)
			)
			(primitives
				(gr_poly
					(pts
						(arc
							(start 0.3048 -0.2032)
							(mid 0.275042 -0.275042)
							(end 0.2032 -0.3048)
						)
						(arc
							(start -0.2032 -0.3048)
							(mid -0.275042 -0.275042)
							(end -0.3048 -0.2032)
						)
						(arc
							(start -0.3048 0.2032)
							(mid -0.275042 0.275042)
							(end -0.2032 0.3048)
						)
						(arc
							(start 0.2032 0.3048)
							(mid 0.275042 0.275042)
							(end 0.3048 0.2032)
						)
					)
					(width 0)
					(fill yes)
				)
			)
		)
		(pad "2" smd custom
			(at 0 0.4445 270)
			(size 0.1524 0.1524)
			(layers "F.Cu" "F.Mask" "F.Paste")
			(net "GND")
			(options
				(clearance outline)
				(anchor circle)
			)
			(primitives
				(gr_poly
					(pts
						(arc
							(start 0.3048 -0.2032)
							(mid 0.275042 -0.275042)
							(end 0.2032 -0.3048)
						)
						(arc
							(start -0.2032 -0.3048)
							(mid -0.275042 -0.275042)
							(end -0.3048 -0.2032)
						)
						(arc
							(start -0.3048 0.2032)
							(mid -0.275042 0.275042)
							(end -0.2032 0.3048)
						)
						(arc
							(start 0.2032 0.3048)
							(mid 0.275042 0.275042)
							(end 0.3048 0.2032)
						)
					)
					(width 0)
					(fill yes)
				)
			)
		)
	)
	(footprint ""
		(layer "F.Cu")
		(at 190.213488 -129.66065 90)
		(property "Reference" "C250"
			(at 0 0 90)
			(layer "F.SilkS")
			(hide yes)
			(effects
				(font
					(size 1.27 1.27)
				)
			)
		)
		(property "Value" "SCD01U16V1KX-GP"
			(at -2.8321 -1.7399 90)
			(unlocked yes)
			(layer "F.Fab")
			(hide yes)
			(effects
				(font
					(size 1.016 1.016)
					(thickness 0.1524)
				)
			)
		)
		(property "Device Type" "C0201H13"
			(at -2.8321 -3.2639 90)
			(unlocked yes)
			(layer "F.Fab")
			(hide yes)
			(effects
				(font
					(size 1.016 1.016)
					(thickness 0.1524)
				)
			)
		)
		(duplicate_pad_numbers_are_jumpers no)
		(fp_rect
			(start -0.2794 0.6477)
			(end 0.2794 -0.6477)
			(stroke
				(width 0)
				(type default)
			)
			(fill no)
			(layer "F.CrtYd")
		)
		(fp_rect
			(start -0.2794 0.6477)
			(end 0.2794 -0.6477)
			(stroke
				(width 0)
				(type default)
			)
			(fill no)
			(layer "F.Fab")
		)
		(pad "1" smd custom
			(at 0 -0.2794 90)
			(size 0.0762 0.0762)
			(layers "F.Cu" "F.Mask" "F.Paste")
			(net "SAS_HDD_RX_P17")
			(options
				(clearance outline)
				(anchor circle)
			)
			(primitives
				(gr_poly
					(pts
						(arc
							(start 0.1524 -0.127)
							(mid 0.137521 -0.162921)
							(end 0.1016 -0.1778)
						)
						(arc
							(start -0.1016 -0.1778)
							(mid -0.137521 -0.162921)
							(end -0.1524 -0.127)
						)
						(arc
							(start -0.1524 0.127)
							(mid -0.137521 0.162921)
							(end -0.1016 0.1778)
						)
						(arc
							(start 0.1016 0.1778)
							(mid 0.137521 0.162921)
							(end 0.1524 0.127)
						)
					)
					(width 0)
					(fill yes)
				)
			)
		)
		(pad "2" smd custom
			(at 0 0.2794 90)
			(size 0.0762 0.0762)
			(layers "F.Cu" "F.Mask" "F.Paste")
			(net "PHY_SCC_B_TO_DRV_B_17_DP")
			(options
				(clearance outline)
				(anchor circle)
			)
			(primitives
				(gr_poly
					(pts
						(arc
							(start 0.1524 -0.127)
							(mid 0.137521 -0.162921)
							(end 0.1016 -0.1778)
						)
						(arc
							(start -0.1016 -0.1778)
							(mid -0.137521 -0.162921)
							(end -0.1524 -0.127)
						)
						(arc
							(start -0.1524 0.127)
							(mid -0.137521 0.162921)
							(end -0.1016 0.1778)
						)
						(arc
							(start 0.1016 0.1778)
							(mid 0.137521 0.162921)
							(end 0.1524 0.127)
						)
					)
					(width 0)
					(fill yes)
				)
			)
		)
	)
	(footprint ""
		(layer "F.Cu")
		(at 14.859 -139.446 -90)
		(property "Reference" "R361"
			(at 0 0 270)
			(layer "F.SilkS")
			(hide yes)
			(effects
				(font
					(size 1.27 1.27)
				)
			)
		)
		(property "Value" "300KR2F-GP"
			(at 0.064008 -3.993896 270)
			(unlocked yes)
			(layer "F.Fab")
			(hide yes)
			(effects
				(font
					(size 1.016 1.016)
					(thickness 0.1524)
				)
			)
		)
		(property "Device Type" "R402H16"
			(at 0.064008 -5.517896 270)
			(unlocked yes)
			(layer "F.Fab")
			(hide yes)
			(effects
				(font
					(size 1.016 1.016)
					(thickness 0.1524)
				)
			)
		)
		(duplicate_pad_numbers_are_jumpers no)
		(fp_line
			(start -0.508 -0.9398)
			(end -0.508 0.9398)
			(stroke
				(width 0.1524)
				(type default)
			)
			(layer "F.SilkS")
		)
		(fp_line
			(start 0.508 -0.9398)
			(end -0.508 -0.9398)
			(stroke
				(width 0.1524)
				(type default)
			)
			(layer "F.SilkS")
		)
		(fp_rect
			(start -0.508 0.9398)
			(end 0.508 -0.9398)
			(stroke
				(width 0)
				(type default)
			)
			(fill no)
			(layer "F.CrtYd")
		)
		(fp_rect
			(start -0.508 0.9398)
			(end 0.508 -0.9398)
			(stroke
				(width 0)
				(type default)
			)
			(fill no)
			(layer "F.Fab")
		)
		(pad "1" smd custom
			(at 0 -0.4445 270)
			(size 0.1397 0.1397)
			(layers "F.Cu" "F.Mask" "F.Paste")
			(net "SW_HDD_N12")
			(options
				(clearance outline)
				(anchor circle)
			)
			(primitives
				(gr_poly
					(pts
						(arc
							(start -0.1778 -0.2794)
							(mid -0.249642 -0.249642)
							(end -0.2794 -0.1778)
						)
						(arc
							(start -0.2794 0.1778)
							(mid -0.249642 0.249642)
							(end -0.1778 0.2794)
						)
						(arc
							(start 0.1778 0.2794)
							(mid 0.249642 0.249642)
							(end 0.2794 0.1778)
						)
						(arc
							(start 0.2794 -0.1778)
							(mid 0.249642 -0.249642)
							(end 0.1778 -0.2794)
						)
					)
					(width 0)
					(fill yes)
				)
			)
		)
		(pad "2" smd custom
			(at 0 0.4445 270)
			(size 0.1397 0.1397)
			(layers "F.Cu" "F.Mask" "F.Paste")
			(net "P12V_B")
			(options
				(clearance outline)
				(anchor circle)
			)
			(primitives
				(gr_poly
					(pts
						(arc
							(start -0.1778 -0.2794)
							(mid -0.249642 -0.249642)
							(end -0.2794 -0.1778)
						)
						(arc
							(start -0.2794 0.1778)
							(mid -0.249642 0.249642)
							(end -0.1778 0.2794)
						)
						(arc
							(start 0.1778 0.2794)
							(mid 0.249642 0.249642)
							(end 0.2794 0.1778)
						)
						(arc
							(start 0.2794 -0.1778)
							(mid 0.249642 -0.249642)
							(end 0.1778 -0.2794)
						)
					)
					(width 0)
					(fill yes)
				)
			)
		)
	)
	(footprint ""
		(layer "F.Cu")
		(at 259.6515 -379.174756 -90)
		(property "Reference" "R1067"
			(at 0 0 270)
			(layer "F.SilkS")
			(hide yes)
			(effects
				(font
					(size 1.27 1.27)
				)
			)
		)
		(property "Value" "0R2J-2-GP"
			(at 0.064008 -3.993896 270)
			(unlocked yes)
			(layer "F.Fab")
			(hide yes)
			(effects
				(font
					(size 1.016 1.016)
					(thickness 0.1524)
				)
			)
		)
		(property "Device Type" "R402H16"
			(at 0.064008 -5.517896 270)
			(unlocked yes)
			(layer "F.Fab")
			(hide yes)
			(effects
				(font
					(size 1.016 1.016)
					(thickness 0.1524)
				)
			)
		)
		(duplicate_pad_numbers_are_jumpers no)
		(fp_line
			(start -0.508 -0.9398)
			(end -0.508 0.9398)
			(stroke
				(width 0.1524)
				(type default)
			)
			(layer "F.SilkS")
		)
		(fp_line
			(start 0.508 -0.9398)
			(end -0.508 -0.9398)
			(stroke
				(width 0.1524)
				(type default)
			)
			(layer "F.SilkS")
		)
		(fp_rect
			(start -0.508 0.9398)
			(end 0.508 -0.9398)
			(stroke
				(width 0)
				(type default)
			)
			(fill no)
			(layer "F.CrtYd")
		)
		(fp_rect
			(start -0.508 0.9398)
			(end 0.508 -0.9398)
			(stroke
				(width 0)
				(type default)
			)
			(fill no)
			(layer "F.Fab")
		)
		(pad "1" smd custom
			(at 0 -0.4445 270)
			(size 0.1397 0.1397)
			(layers "F.Cu" "F.Mask" "F.Paste")
			(net "DRAWER_OUT#_C")
			(options
				(clearance outline)
				(anchor circle)
			)
			(primitives
				(gr_poly
					(pts
						(arc
							(start -0.1778 -0.2794)
							(mid -0.249642 -0.249642)
							(end -0.2794 -0.1778)
						)
						(arc
							(start -0.2794 0.1778)
							(mid -0.249642 0.249642)
							(end -0.1778 0.2794)
						)
						(arc
							(start 0.1778 0.2794)
							(mid 0.249642 0.249642)
							(end 0.2794 0.1778)
						)
						(arc
							(start 0.2794 -0.1778)
							(mid 0.249642 -0.249642)
							(end 0.1778 -0.2794)
						)
					)
					(width 0)
					(fill yes)
				)
			)
		)
		(pad "2" smd custom
			(at 0 0.4445 270)
			(size 0.1397 0.1397)
			(layers "F.Cu" "F.Mask" "F.Paste")
			(net "DRAWER_MOSFET_G")
			(options
				(clearance outline)
				(anchor circle)
			)
			(primitives
				(gr_poly
					(pts
						(arc
							(start -0.1778 -0.2794)
							(mid -0.249642 -0.249642)
							(end -0.2794 -0.1778)
						)
						(arc
							(start -0.2794 0.1778)
							(mid -0.249642 0.249642)
							(end -0.1778 0.2794)
						)
						(arc
							(start 0.1778 0.2794)
							(mid 0.249642 0.249642)
							(end 0.2794 0.1778)
						)
						(arc
							(start 0.2794 -0.1778)
							(mid 0.249642 -0.249642)
							(end 0.1778 -0.2794)
						)
					)
					(width 0)
					(fill yes)
				)
			)
		)
	)
	(footprint ""
		(layer "F.Cu")
		(at 362.966 -147.066 -90)
		(property "Reference" "R506"
			(at 0 0 270)
			(layer "F.SilkS")
			(hide yes)
			(effects
				(font
					(size 1.27 1.27)
				)
			)
		)
		(property "Value" "2R6F-GP"
			(at -0.0508 -4.8514 270)
			(unlocked yes)
			(layer "F.Fab")
			(hide yes)
			(effects
				(font
					(size 1.016 1.016)
					(thickness 0.1524)
				)
			)
		)
		(property "Device Type" "R1206H26"
			(at 0 -6.3754 270)
			(unlocked yes)
			(layer "F.Fab")
			(hide yes)
			(effects
				(font
					(size 1.016 1.016)
					(thickness 0.1524)
				)
			)
		)
		(duplicate_pad_numbers_are_jumpers no)
		(fp_line
			(start -1.016 2.2352)
			(end -1.016 -2.2352)
			(stroke
				(width 0.1524)
				(type default)
			)
			(layer "F.SilkS")
		)
		(fp_line
			(start 1.016 2.2352)
			(end -1.016 2.2352)
			(stroke
				(width 0.1524)
				(type default)
			)
			(layer "F.SilkS")
		)
		(fp_line
			(start -1.016 -2.2352)
			(end 1.016 -2.2352)
			(stroke
				(width 0.1524)
				(type default)
			)
			(layer "F.SilkS")
		)
		(fp_line
			(start 1.016 -2.2352)
			(end 1.016 2.2352)
			(stroke
				(width 0.1524)
				(type default)
			)
			(layer "F.SilkS")
		)
		(fp_rect
			(start -1.0922 2.3114)
			(end 1.0922 -2.3114)
			(stroke
				(width 0)
				(type default)
			)
			(fill no)
			(layer "F.CrtYd")
		)
		(fp_poly
			(pts
				(xy -1.0922 -2.3114) (xy 1.0922 -2.3114) (xy 1.0922 2.3114) (xy -1.0922 2.3114)
			)
			(stroke
				(width 0)
				(type default)
			)
			(fill no)
			(layer "F.Fab")
		)
		(pad "1" smd rect
			(at 0 -1.397 270)
			(size 1.651 1.27)
			(layers "F.Cu" "F.Mask" "F.Paste")
			(net "P5V_HDD19")
		)
		(pad "2" smd rect
			(at 0 1.397 270)
			(size 1.651 1.27)
			(layers "F.Cu" "F.Mask" "F.Paste")
			(net "5V_PRE_19")
		)
	)
	(footprint ""
		(layer "F.Cu")
		(at 50.546 -265.684 90)
		(property "Reference" "R177"
			(at 0 0 90)
			(layer "F.SilkS")
			(hide yes)
			(effects
				(font
					(size 1.27 1.27)
				)
			)
		)
		(property "Value" "2R6F-GP"
			(at -0.0508 -4.8514 90)
			(unlocked yes)
			(layer "F.Fab")
			(hide yes)
			(effects
				(font
					(size 1.016 1.016)
					(thickness 0.1524)
				)
			)
		)
		(property "Device Type" "R1206H26"
			(at 0 -6.3754 90)
			(unlocked yes)
			(layer "F.Fab")
			(hide yes)
			(effects
				(font
					(size 1.016 1.016)
					(thickness 0.1524)
				)
			)
		)
		(duplicate_pad_numbers_are_jumpers no)
		(fp_line
			(start 1.016 -2.2352)
			(end 1.016 2.2352)
			(stroke
				(width 0.1524)
				(type default)
			)
			(layer "F.SilkS")
		)
		(fp_line
			(start -1.016 -2.2352)
			(end 1.016 -2.2352)
			(stroke
				(width 0.1524)
				(type default)
			)
			(layer "F.SilkS")
		)
		(fp_line
			(start 1.016 2.2352)
			(end -1.016 2.2352)
			(stroke
				(width 0.1524)
				(type default)
			)
			(layer "F.SilkS")
		)
		(fp_line
			(start -1.016 2.2352)
			(end -1.016 -2.2352)
			(stroke
				(width 0.1524)
				(type default)
			)
			(layer "F.SilkS")
		)
		(fp_rect
			(start -1.0922 2.3114)
			(end 1.0922 -2.3114)
			(stroke
				(width 0)
				(type default)
			)
			(fill no)
			(layer "F.CrtYd")
		)
		(fp_poly
			(pts
				(xy -1.0922 -2.3114) (xy 1.0922 -2.3114) (xy 1.0922 2.3114) (xy -1.0922 2.3114)
			)
			(stroke
				(width 0)
				(type default)
			)
			(fill no)
			(layer "F.Fab")
		)
		(pad "1" smd rect
			(at 0 -1.397 90)
			(size 1.651 1.27)
			(layers "F.Cu" "F.Mask" "F.Paste")
			(net "P12V_HDD1")
		)
		(pad "2" smd rect
			(at 0 1.397 90)
			(size 1.651 1.27)
			(layers "F.Cu" "F.Mask" "F.Paste")
			(net "12V_PRE_1")
		)
	)
	(footprint ""
		(layer "F.Cu")
		(at 19.701002 -229.49535 180)
		(property "Reference" "R1115"
			(at 0 0 180)
			(layer "F.SilkS")
			(hide yes)
			(effects
				(font
					(size 1.27 1.27)
				)
			)
		)
		(property "Value" "619KR2F-GP"
			(at 0.064008 -3.993896 180)
			(unlocked yes)
			(layer "F.Fab")
			(hide yes)
			(effects
				(font
					(size 1.016 1.016)
					(thickness 0.1524)
				)
			)
		)
		(property "Device Type" "R402H16"
			(at 0.064008 -5.517896 180)
			(unlocked yes)
			(layer "F.Fab")
			(hide yes)
			(effects
				(font
					(size 1.016 1.016)
					(thickness 0.1524)
				)
			)
		)
		(duplicate_pad_numbers_are_jumpers no)
		(fp_line
			(start 0.508 -0.9398)
			(end -0.508 -0.9398)
			(stroke
				(width 0.1524)
				(type default)
			)
			(layer "F.SilkS")
		)
		(fp_line
			(start -0.508 -0.9398)
			(end -0.508 0.9398)
			(stroke
				(width 0.1524)
				(type default)
			)
			(layer "F.SilkS")
		)
		(fp_rect
			(start -0.508 0.9398)
			(end 0.508 -0.9398)
			(stroke
				(width 0)
				(type default)
			)
			(fill no)
			(layer "F.CrtYd")
		)
		(fp_rect
			(start -0.508 0.9398)
			(end 0.508 -0.9398)
			(stroke
				(width 0)
				(type default)
			)
			(fill no)
			(layer "F.Fab")
		)
		(pad "1" smd custom
			(at 0 -0.4445 180)
			(size 0.1397 0.1397)
			(layers "F.Cu" "F.Mask" "F.Paste")
			(net "P5V_B_1_RF")
			(options
				(clearance outline)
				(anchor circle)
			)
			(primitives
				(gr_poly
					(pts
						(arc
							(start -0.1778 -0.2794)
							(mid -0.249642 -0.249642)
							(end -0.2794 -0.1778)
						)
						(arc
							(start -0.2794 0.1778)
							(mid -0.249642 0.249642)
							(end -0.1778 0.2794)
						)
						(arc
							(start 0.1778 0.2794)
							(mid 0.249642 0.249642)
							(end 0.2794 0.1778)
						)
						(arc
							(start 0.2794 -0.1778)
							(mid 0.249642 -0.249642)
							(end 0.1778 -0.2794)
						)
					)
					(width 0)
					(fill yes)
				)
			)
		)
		(pad "2" smd custom
			(at 0 0.4445 180)
			(size 0.1397 0.1397)
			(layers "F.Cu" "F.Mask" "F.Paste")
			(net "AGND_P5V_B_1")
			(options
				(clearance outline)
				(anchor circle)
			)
			(primitives
				(gr_poly
					(pts
						(arc
							(start -0.1778 -0.2794)
							(mid -0.249642 -0.249642)
							(end -0.2794 -0.1778)
						)
						(arc
							(start -0.2794 0.1778)
							(mid -0.249642 0.249642)
							(end -0.1778 0.2794)
						)
						(arc
							(start 0.1778 0.2794)
							(mid 0.249642 0.249642)
							(end 0.2794 0.1778)
						)
						(arc
							(start 0.2794 -0.1778)
							(mid 0.249642 -0.249642)
							(end 0.1778 -0.2794)
						)
					)
					(width 0)
					(fill yes)
				)
			)
		)
	)
)
